(kicad_pcb
	(version 20260206)
	(generator "pcbnew")
	(generator_version "10.0")
	(general
		(thickness 1.6)
		(legacy_teardrops no)
	)
	(paper "A4")
	(title_block
		(title "peb — Lightning_PEB_BRD.brd")
		(comment 1 "Lightning (Wiwynn / Facebook NVMe JBOF) / footprints 321-327 of 2563")
	)
	(layers
		(0 "F.Cu" signal "TOP")
		(4 "In1.Cu" signal "L2GND")
		(6 "In2.Cu" signal "L3")
		(8 "In3.Cu" signal "L4VCC")
		(10 "In4.Cu" signal "L5VCC")
		(12 "In5.Cu" signal "L6")
		(14 "In6.Cu" signal "L7GND")
		(2 "B.Cu" signal "BOTTOM")
		(9 "F.Adhes" user "F.Adhesive")
		(11 "B.Adhes" user "B.Adhesive")
		(13 "F.Paste" user "Package Geometry/Pastemask Top")
		(15 "B.Paste" user "Package Geometry/Pastemask Bottom")
		(5 "F.SilkS" user "Ref Des/Silkscreen Top")
		(7 "B.SilkS" user "Ref Des/Silkscreen Bottom")
		(1 "F.Mask" user "Board Geometry/Soldermask Top")
		(3 "B.Mask" user "Board Geometry/Soldermask Bottom")
		(17 "Dwgs.User" user "User.Drawings")
		(19 "Cmts.User" user "User.Comments")
		(21 "Eco1.User" user "User.Eco1")
		(23 "Eco2.User" user "User.Eco2")
		(25 "Edge.Cuts" user "Board Geometry/Outline")
		(27 "Margin" user)
		(31 "F.CrtYd" user "Package Geometry/Place Bound Top")
		(29 "B.CrtYd" user "Package Geometry/Place Bound Bottom")
		(35 "F.Fab" user "Ref Des/Assembly Top")
		(33 "B.Fab" user "Ref Des/Assembly Bottom")
	)
	(footprint ""
		(layer "F.Cu")
		(at 39.0398 -188.5696 180)
		(property "Reference" "R874"
			(at 0 0 180)
			(layer "F.SilkS")
			(hide yes)
			(effects
				(font
					(size 1.27 1.27)
				)
			)
		)
		(property "Value" "10KR2F-2-GP"
			(at 0.064008 -3.993896 180)
			(unlocked yes)
			(layer "F.Fab")
			(hide yes)
			(effects
				(font
					(size 1.016 1.016)
					(thickness 0.1524)
				)
			)
		)
		(property "Device Type" "R402H16"
			(at 0.064008 -5.517896 180)
			(unlocked yes)
			(layer "F.Fab")
			(hide yes)
			(effects
				(font
					(size 1.016 1.016)
					(thickness 0.1524)
				)
			)
		)
		(duplicate_pad_numbers_are_jumpers no)
		(fp_line
			(start 0.508 -0.9398)
			(end -0.508 -0.9398)
			(stroke
				(width 0.1524)
				(type default)
			)
			(layer "F.SilkS")
		)
		(fp_line
			(start -0.508 -0.9398)
			(end -0.508 0.9398)
			(stroke
				(width 0.1524)
				(type default)
			)
			(layer "F.SilkS")
		)
		(fp_rect
			(start -0.508 0.9398)
			(end 0.508 -0.9398)
			(stroke
				(width 0)
				(type default)
			)
			(fill no)
			(layer "F.CrtYd")
		)
		(fp_rect
			(start -0.508 0.9398)
			(end 0.508 -0.9398)
			(stroke
				(width 0)
				(type default)
			)
			(fill no)
			(layer "F.Fab")
		)
		(pad "1" smd custom
			(at 0 -0.4445 180)
			(size 0.1397 0.1397)
			(layers "F.Cu" "F.Mask" "F.Paste")
			(net "I2C9_BUF_READY")
			(options
				(clearance outline)
				(anchor circle)
			)
			(primitives
				(gr_poly
					(pts
						(arc
							(start -0.1778 -0.2794)
							(mid -0.249642 -0.249642)
							(end -0.2794 -0.1778)
						)
						(arc
							(start -0.2794 0.1778)
							(mid -0.249642 0.249642)
							(end -0.1778 0.2794)
						)
						(arc
							(start 0.1778 0.2794)
							(mid 0.249642 0.249642)
							(end 0.2794 0.1778)
						)
						(arc
							(start 0.2794 -0.1778)
							(mid 0.249642 -0.249642)
							(end 0.1778 -0.2794)
						)
					)
					(width 0)
					(fill yes)
				)
			)
		)
		(pad "2" smd custom
			(at 0 0.4445 180)
			(size 0.1397 0.1397)
			(layers "F.Cu" "F.Mask" "F.Paste")
			(net "P3V3_STBY")
			(options
				(clearance outline)
				(anchor circle)
			)
			(primitives
				(gr_poly
					(pts
						(arc
							(start -0.1778 -0.2794)
							(mid -0.249642 -0.249642)
							(end -0.2794 -0.1778)
						)
						(arc
							(start -0.2794 0.1778)
							(mid -0.249642 0.249642)
							(end -0.1778 0.2794)
						)
						(arc
							(start 0.1778 0.2794)
							(mid 0.249642 0.249642)
							(end 0.2794 0.1778)
						)
						(arc
							(start 0.2794 -0.1778)
							(mid 0.249642 -0.249642)
							(end 0.1778 -0.2794)
						)
					)
					(width 0)
					(fill yes)
				)
			)
		)
	)
	(footprint ""
		(layer "F.Cu")
		(at 147.365212 -59.936126)
		(property "Reference" "PC193"
			(at 0 0 0)
			(layer "F.SilkS")
			(hide yes)
			(effects
				(font
					(size 1.27 1.27)
				)
			)
		)
		(property "Value" "SC1U16V3KX-5GP"
			(at 0 -2.8194 0)
			(unlocked yes)
			(layer "F.Fab")
			(hide yes)
			(effects
				(font
					(size 1.016 1.016)
					(thickness 0.1524)
				)
			)
		)
		(property "Device Type" "C603H36"
			(at 0 -4.3434 0)
			(unlocked yes)
			(layer "F.Fab")
			(hide yes)
			(effects
				(font
					(size 1.016 1.016)
					(thickness 0.1524)
				)
			)
		)
		(duplicate_pad_numbers_are_jumpers no)
		(fp_line
			(start 0.508 0)
			(end -0.508 0)
			(stroke
				(width 0.2032)
				(type default)
			)
			(layer "F.SilkS")
		)
		(fp_rect
			(start -0.5842 1.3335)
			(end 0.5842 -1.3335)
			(stroke
				(width 0)
				(type default)
			)
			(fill no)
			(layer "F.CrtYd")
		)
		(fp_rect
			(start -0.5842 1.3335)
			(end 0.5842 -1.3335)
			(stroke
				(width 0)
				(type default)
			)
			(fill no)
			(layer "F.Fab")
		)
		(pad "1" smd custom
			(at 0 -0.762)
			(size 0.2159 0.2159)
			(layers "F.Cu" "F.Mask" "F.Paste")
			(net "P0V9_VREG")
			(options
				(clearance outline)
				(anchor circle)
			)
			(primitives
				(gr_poly
					(pts
						(arc
							(start -0.3302 -0.4318)
							(mid -0.402042 -0.402042)
							(end -0.4318 -0.3302)
						)
						(arc
							(start -0.4318 0.3302)
							(mid -0.402042 0.402042)
							(end -0.3302 0.4318)
						)
						(arc
							(start 0.3302 0.4318)
							(mid 0.402042 0.402042)
							(end 0.4318 0.3302)
						)
						(arc
							(start 0.4318 -0.3302)
							(mid 0.402042 -0.402042)
							(end 0.3302 -0.4318)
						)
					)
					(width 0)
					(fill yes)
				)
			)
		)
		(pad "2" smd custom
			(at 0 0.762)
			(size 0.2159 0.2159)
			(layers "F.Cu" "F.Mask" "F.Paste")
			(net "GND")
			(options
				(clearance outline)
				(anchor circle)
			)
			(primitives
				(gr_poly
					(pts
						(arc
							(start -0.3302 -0.4318)
							(mid -0.402042 -0.402042)
							(end -0.4318 -0.3302)
						)
						(arc
							(start -0.4318 0.3302)
							(mid -0.402042 0.402042)
							(end -0.3302 0.4318)
						)
						(arc
							(start 0.3302 0.4318)
							(mid 0.402042 0.402042)
							(end 0.4318 0.3302)
						)
						(arc
							(start 0.4318 -0.3302)
							(mid 0.402042 -0.402042)
							(end 0.3302 -0.4318)
						)
					)
					(width 0)
					(fill yes)
				)
			)
		)
	)
	(footprint ""
		(layer "F.Cu")
		(at 151.527002 -72.823832 90)
		(property "Reference" "PC211"
			(at 0 0 90)
			(layer "F.SilkS")
			(hide yes)
			(effects
				(font
					(size 1.27 1.27)
				)
			)
		)
		(property "Value" "SC22U25V6KX-GP-U"
			(at -2.860802 -5.279644 90)
			(unlocked yes)
			(layer "F.Fab")
			(hide yes)
			(effects
				(font
					(size 1.016 1.016)
					(thickness 0.1524)
				)
			)
		)
		(property "Device Type" "C1206-TO0D3H75"
			(at -2.860802 -6.803644 90)
			(unlocked yes)
			(layer "F.Fab")
			(hide yes)
			(effects
				(font
					(size 1.016 1.016)
					(thickness 0.1524)
				)
			)
		)
		(duplicate_pad_numbers_are_jumpers no)
		(fp_line
			(start 1.3081 -2.3749)
			(end 1.3081 2.3749)
			(stroke
				(width 0.1524)
				(type default)
			)
			(layer "F.SilkS")
		)
		(fp_line
			(start -1.3081 -2.3749)
			(end 1.3081 -2.3749)
			(stroke
				(width 0.1524)
				(type default)
			)
			(layer "F.SilkS")
		)
		(fp_line
			(start 1.3081 2.3749)
			(end -1.3081 2.3749)
			(stroke
				(width 0.1524)
				(type default)
			)
			(layer "F.SilkS")
		)
		(fp_line
			(start -1.3081 2.3749)
			(end -1.3081 -2.3749)
			(stroke
				(width 0.1524)
				(type default)
			)
			(layer "F.SilkS")
		)
		(fp_rect
			(start -0.8001 1.6002)
			(end 0.8001 -1.6002)
			(stroke
				(width 0)
				(type default)
			)
			(fill no)
			(layer "F.CrtYd")
		)
		(fp_poly
			(pts
				(xy -1.5621 2.4511) (xy -1.5621 1.6002) (xy 0.8001 1.6002) (xy 0.8001 -1.6002) (xy -0.8001 -1.6002)
				(xy -0.8001 1.5875) (xy -1.5621 1.5875) (xy -1.5621 -2.4511) (xy 1.5621 -2.4511) (xy 1.5621 2.4511)
			)
			(stroke
				(width 0)
				(type default)
			)
			(fill no)
			(layer "F.CrtYd")
		)
		(fp_rect
			(start -1.5621 2.4511)
			(end 1.5621 -2.4511)
			(stroke
				(width 0)
				(type default)
			)
			(fill no)
			(layer "F.Fab")
		)
		(pad "1" smd rect
			(at 0 -1.392936 90)
			(size 2.1082 1.4478)
			(layers "F.Cu" "F.Mask" "F.Paste")
			(net "P0V9_VIN")
		)
		(pad "2" smd rect
			(at 0 1.392936 90)
			(size 2.1082 1.4478)
			(layers "F.Cu" "F.Mask" "F.Paste")
			(net "GND")
		)
	)
	(footprint ""
		(layer "F.Cu")
		(at 224.893124 -190.601092)
		(property "Reference" "R7942"
			(at 0 0 0)
			(layer "F.SilkS")
			(hide yes)
			(effects
				(font
					(size 1.27 1.27)
				)
			)
		)
		(property "Value" "0R2J-2-GP"
			(at 0.064008 -3.993896 0)
			(unlocked yes)
			(layer "F.Fab")
			(hide yes)
			(effects
				(font
					(size 1.016 1.016)
					(thickness 0.1524)
				)
			)
		)
		(property "Device Type" "R402H16"
			(at 0.064008 -5.517896 0)
			(unlocked yes)
			(layer "F.Fab")
			(hide yes)
			(effects
				(font
					(size 1.016 1.016)
					(thickness 0.1524)
				)
			)
		)
		(duplicate_pad_numbers_are_jumpers no)
		(fp_line
			(start -0.508 -0.9398)
			(end -0.508 0.9398)
			(stroke
				(width 0.1524)
				(type default)
			)
			(layer "F.SilkS")
		)
		(fp_line
			(start 0.508 -0.9398)
			(end -0.508 -0.9398)
			(stroke
				(width 0.1524)
				(type default)
			)
			(layer "F.SilkS")
		)
		(fp_rect
			(start -0.508 0.9398)
			(end 0.508 -0.9398)
			(stroke
				(width 0)
				(type default)
			)
			(fill no)
			(layer "F.CrtYd")
		)
		(fp_rect
			(start -0.508 0.9398)
			(end 0.508 -0.9398)
			(stroke
				(width 0)
				(type default)
			)
			(fill no)
			(layer "F.Fab")
		)
		(pad "1" smd custom
			(at 0 -0.4445)
			(size 0.1397 0.1397)
			(layers "F.Cu" "F.Mask" "F.Paste")
			(net "SSD_ATNLED#8")
			(options
				(clearance outline)
				(anchor circle)
			)
			(primitives
				(gr_poly
					(pts
						(arc
							(start -0.1778 -0.2794)
							(mid -0.249642 -0.249642)
							(end -0.2794 -0.1778)
						)
						(arc
							(start -0.2794 0.1778)
							(mid -0.249642 0.249642)
							(end -0.1778 0.2794)
						)
						(arc
							(start 0.1778 0.2794)
							(mid 0.249642 0.249642)
							(end 0.2794 0.1778)
						)
						(arc
							(start 0.2794 -0.1778)
							(mid 0.249642 -0.249642)
							(end 0.1778 -0.2794)
						)
					)
					(width 0)
					(fill yes)
				)
			)
		)
		(pad "2" smd custom
			(at 0 0.4445)
			(size 0.1397 0.1397)
			(layers "F.Cu" "F.Mask" "F.Paste")
			(net "SSD_ATNLED#8_R")
			(options
				(clearance outline)
				(anchor circle)
			)
			(primitives
				(gr_poly
					(pts
						(arc
							(start -0.1778 -0.2794)
							(mid -0.249642 -0.249642)
							(end -0.2794 -0.1778)
						)
						(arc
							(start -0.2794 0.1778)
							(mid -0.249642 0.249642)
							(end -0.1778 0.2794)
						)
						(arc
							(start 0.1778 0.2794)
							(mid 0.249642 0.249642)
							(end 0.2794 0.1778)
						)
						(arc
							(start 0.2794 -0.1778)
							(mid 0.249642 -0.249642)
							(end 0.1778 -0.2794)
						)
					)
					(width 0)
					(fill yes)
				)
			)
		)
	)
	(footprint ""
		(layer "F.Cu")
		(at 26.318718 -84.96681)
		(property "Reference" "R646"
			(at 0 0 0)
			(layer "F.SilkS")
			(hide yes)
			(effects
				(font
					(size 1.27 1.27)
				)
			)
		)
		(property "Value" "10KR2F-2-GP"
			(at 0.064008 -3.993896 0)
			(unlocked yes)
			(layer "F.Fab")
			(hide yes)
			(effects
				(font
					(size 1.016 1.016)
					(thickness 0.1524)
				)
			)
		)
		(property "Device Type" "R402H16"
			(at 0.064008 -5.517896 0)
			(unlocked yes)
			(layer "F.Fab")
			(hide yes)
			(effects
				(font
					(size 1.016 1.016)
					(thickness 0.1524)
				)
			)
		)
		(duplicate_pad_numbers_are_jumpers no)
		(fp_line
			(start -0.508 -0.9398)
			(end -0.508 0.9398)
			(stroke
				(width 0.1524)
				(type default)
			)
			(layer "F.SilkS")
		)
		(fp_line
			(start 0.508 -0.9398)
			(end -0.508 -0.9398)
			(stroke
				(width 0.1524)
				(type default)
			)
			(layer "F.SilkS")
		)
		(fp_rect
			(start -0.508 0.9398)
			(end 0.508 -0.9398)
			(stroke
				(width 0)
				(type default)
			)
			(fill no)
			(layer "F.CrtYd")
		)
		(fp_rect
			(start -0.508 0.9398)
			(end 0.508 -0.9398)
			(stroke
				(width 0)
				(type default)
			)
			(fill no)
			(layer "F.Fab")
		)
		(pad "1" smd custom
			(at 0 -0.4445)
			(size 0.1397 0.1397)
			(layers "F.Cu" "F.Mask" "F.Paste")
			(net "P3V3_STBY")
			(options
				(clearance outline)
				(anchor circle)
			)
			(primitives
				(gr_poly
					(pts
						(arc
							(start -0.1778 -0.2794)
							(mid -0.249642 -0.249642)
							(end -0.2794 -0.1778)
						)
						(arc
							(start -0.2794 0.1778)
							(mid -0.249642 0.249642)
							(end -0.1778 0.2794)
						)
						(arc
							(start 0.1778 0.2794)
							(mid 0.249642 0.249642)
							(end 0.2794 0.1778)
						)
						(arc
							(start 0.2794 -0.1778)
							(mid 0.249642 -0.249642)
							(end 0.1778 -0.2794)
						)
					)
					(width 0)
					(fill yes)
				)
			)
		)
		(pad "2" smd custom
			(at 0 0.4445)
			(size 0.1397 0.1397)
			(layers "F.Cu" "F.Mask" "F.Paste")
			(net "PHY_WAKE_N")
			(options
				(clearance outline)
				(anchor circle)
			)
			(primitives
				(gr_poly
					(pts
						(arc
							(start -0.1778 -0.2794)
							(mid -0.249642 -0.249642)
							(end -0.2794 -0.1778)
						)
						(arc
							(start -0.2794 0.1778)
							(mid -0.249642 0.249642)
							(end -0.1778 0.2794)
						)
						(arc
							(start 0.1778 0.2794)
							(mid 0.249642 0.249642)
							(end 0.2794 0.1778)
						)
						(arc
							(start 0.2794 -0.1778)
							(mid 0.249642 -0.249642)
							(end 0.1778 -0.2794)
						)
					)
					(width 0)
					(fill yes)
				)
			)
		)
	)
	(footprint ""
		(layer "F.Cu")
		(at 99.008184 -212.420454 180)
		(property "Reference" "C157"
			(at 0 0 180)
			(layer "F.SilkS")
			(hide yes)
			(effects
				(font
					(size 1.27 1.27)
				)
			)
		)
		(property "Value" "SCD22U10V2KX-1GP"
			(at 1.1811 -2.7051 180)
			(unlocked yes)
			(layer "F.Fab")
			(hide yes)
			(effects
				(font
					(size 1.016 1.016)
					(thickness 0.1524)
				)
			)
		)
		(property "Device Type" "C402H22"
			(at 1.1811 -4.2291 180)
			(unlocked yes)
			(layer "F.Fab")
			(hide yes)
			(effects
				(font
					(size 1.016 1.016)
					(thickness 0.1524)
				)
			)
		)
		(duplicate_pad_numbers_are_jumpers no)
		(fp_rect
			(start -0.4318 0.9525)
			(end 0.4318 -0.9525)
			(stroke
				(width 0)
				(type default)
			)
			(fill no)
			(layer "F.CrtYd")
		)
		(fp_rect
			(start -0.4318 0.9525)
			(end 0.4318 -0.9525)
			(stroke
				(width 0)
				(type default)
			)
			(fill no)
			(layer "F.Fab")
		)
		(pad "1" smd custom
			(at 0 -0.4445 180)
			(size 0.1524 0.1524)
			(layers "F.Cu" "F.Mask" "F.Paste")
			(net "PCIE_TX_CAP_N63")
			(options
				(clearance outline)
				(anchor circle)
			)
			(primitives
				(gr_poly
					(pts
						(arc
							(start 0.3048 -0.2032)
							(mid 0.275042 -0.275042)
							(end 0.2032 -0.3048)
						)
						(arc
							(start -0.2032 -0.3048)
							(mid -0.275042 -0.275042)
							(end -0.3048 -0.2032)
						)
						(arc
							(start -0.3048 0.2032)
							(mid -0.275042 0.275042)
							(end -0.2032 0.3048)
						)
						(arc
							(start 0.2032 0.3048)
							(mid 0.275042 0.275042)
							(end 0.3048 0.2032)
						)
					)
					(width 0)
					(fill yes)
				)
			)
		)
		(pad "2" smd custom
			(at 0 0.4445 180)
			(size 0.1524 0.1524)
			(layers "F.Cu" "F.Mask" "F.Paste")
			(net "PCIE_TX_N63")
			(options
				(clearance outline)
				(anchor circle)
			)
			(primitives
				(gr_poly
					(pts
						(arc
							(start 0.3048 -0.2032)
							(mid 0.275042 -0.275042)
							(end 0.2032 -0.3048)
						)
						(arc
							(start -0.2032 -0.3048)
							(mid -0.275042 -0.275042)
							(end -0.3048 -0.2032)
						)
						(arc
							(start -0.3048 0.2032)
							(mid -0.275042 0.275042)
							(end -0.2032 0.3048)
						)
						(arc
							(start 0.2032 0.3048)
							(mid 0.275042 0.275042)
							(end 0.3048 0.2032)
						)
					)
					(width 0)
					(fill yes)
				)
			)
		)
	)
	(footprint ""
		(layer "F.Cu")
		(at 182.448708 -1.276096)
		(property "Reference" "R671"
			(at 0 0 0)
			(layer "F.SilkS")
			(hide yes)
			(effects
				(font
					(size 1.27 1.27)
				)
			)
		)
		(property "Value" "0R2J-2-GP"
			(at 0.064008 -3.993896 0)
			(unlocked yes)
			(layer "F.Fab")
			(hide yes)
			(effects
				(font
					(size 1.016 1.016)
					(thickness 0.1524)
				)
			)
		)
		(property "Device Type" "R402H16"
			(at 0.064008 -5.517896 0)
			(unlocked yes)
			(layer "F.Fab")
			(hide yes)
			(effects
				(font
					(size 1.016 1.016)
					(thickness 0.1524)
				)
			)
		)
		(duplicate_pad_numbers_are_jumpers no)
		(fp_line
			(start -0.508 -0.9398)
			(end -0.508 0.9398)
			(stroke
				(width 0.1524)
				(type default)
			)
			(layer "F.SilkS")
		)
		(fp_line
			(start 0.508 -0.9398)
			(end -0.508 -0.9398)
			(stroke
				(width 0.1524)
				(type default)
			)
			(layer "F.SilkS")
		)
		(fp_rect
			(start -0.508 0.9398)
			(end 0.508 -0.9398)
			(stroke
				(width 0)
				(type default)
			)
			(fill no)
			(layer "F.CrtYd")
		)
		(fp_rect
			(start -0.508 0.9398)
			(end 0.508 -0.9398)
			(stroke
				(width 0)
				(type default)
			)
			(fill no)
			(layer "F.Fab")
		)
		(pad "1" smd custom
			(at 0 -0.4445)
			(size 0.1397 0.1397)
			(layers "F.Cu" "F.Mask" "F.Paste")
			(net "HOST2_RST_N_C")
			(options
				(clearance outline)
				(anchor circle)
			)
			(primitives
				(gr_poly
					(pts
						(arc
							(start -0.1778 -0.2794)
							(mid -0.249642 -0.249642)
							(end -0.2794 -0.1778)
						)
						(arc
							(start -0.2794 0.1778)
							(mid -0.249642 0.249642)
							(end -0.1778 0.2794)
						)
						(arc
							(start 0.1778 0.2794)
							(mid 0.249642 0.249642)
							(end 0.2794 0.1778)
						)
						(arc
							(start 0.2794 -0.1778)
							(mid 0.249642 -0.249642)
							(end 0.1778 -0.2794)
						)
					)
					(width 0)
					(fill yes)
				)
			)
		)
		(pad "2" smd custom
			(at 0 0.4445)
			(size 0.1397 0.1397)
			(layers "F.Cu" "F.Mask" "F.Paste")
			(net "P3V3_STBY")
			(options
				(clearance outline)
				(anchor circle)
			)
			(primitives
				(gr_poly
					(pts
						(arc
							(start -0.1778 -0.2794)
							(mid -0.249642 -0.249642)
							(end -0.2794 -0.1778)
						)
						(arc
							(start -0.2794 0.1778)
							(mid -0.249642 0.249642)
							(end -0.1778 0.2794)
						)
						(arc
							(start 0.1778 0.2794)
							(mid 0.249642 0.249642)
							(end 0.2794 0.1778)
						)
						(arc
							(start 0.2794 -0.1778)
							(mid 0.249642 -0.249642)
							(end 0.1778 -0.2794)
						)
					)
					(width 0)
					(fill yes)
				)
			)
		)
	)
)
